# T6G (Grand Teton) — schematic netlist excerpt (pin names and nets, part order shuffled) for the footprints in the layout excerpt that follows; sources: Cadence DE-HDL packaged netlist, KiCad conversion of 04192023_DAF0TMB3IC0_F0TG_MB_C_brd_V02_OCP.brd

PU6504  ISL99390FRZTR5935  ISL99390FRZ-TR5935 IC  pkg QFN21_6X5XB  page 363
  VOS  = P0V9_RETIMER_CPU0_VOS2
  AGND  = GND
  VCC  = P0V9_RETIMER_CPU0_VCC2
  PVCC  = P0V9_RETIMER_CPU0_PVCC
  PGND1  = GND
  GL1  = NC_PV09_RETIMER_CPU0_GL1_2
  PGND2  = GND
  SW  = SW_P0V9_RETIMER_CPU0_SW2
  VIN1  = SW_P12V_AUX_P0V9_RETIMER_CPU0_FLT
  VIN2  = SW_P12V_AUX_P0V9_RETIMER_CPU0_FLT
  DNC  = NC_PV09_RETIMER_CPU0_DNC2
  PHASE  = SW_P0V9_RETIMER_CPU0_PH2
  BOOT  = SW_P0V9_RETIMER_CPU0_BOOT2
  PWM  = P0V9_RETIMER_CPU0_PWM2
  EN  = P0V9_RETIMER_CPU0_VCC2
  TOUT_FLT  = P0V9_RETIMER_CPU0_TEMP0
  LSET  = P0V9_RETIMER_CPU0_LSET2
  IOUT  = P0V9_RETIMER_CPU0_IMON2
  REFIN  = PV09_RETIMER_CPU0_VCCS
  PGND3  = GND
  GL2  = NC_PV09_RETIMER_CPU0_GL2_2

(kicad_pcb
	(version 20260206)
	(generator "pcbnew")
	(generator_version "10.0")
	(general
		(thickness 1.6)
		(legacy_teardrops no)
	)
	(paper "A4")
	(title_block
		(title "04192023_DAF0TMB3IC0_F0TG_MB_C_brd_V02_OCP.brd")
		(comment 1 "Grand Teton / footprint 4249 of 8354 (PU6504), pads 1-21 of 21")
	)
	(layers
		(0 "F.Cu" signal "TOP")
		(4 "In1.Cu" signal "GND")
		(6 "In2.Cu" signal "IN1")
		(8 "In3.Cu" signal "GND1")
		(10 "In4.Cu" signal "IN2")
		(12 "In5.Cu" signal "GND2")
		(14 "In6.Cu" signal "IN3")
		(16 "In7.Cu" signal "GND3")
		(18 "In8.Cu" signal "VCC")
		(20 "In9.Cu" signal "VCC1")
		(22 "In10.Cu" signal "GND4")
		(24 "In11.Cu" signal "IN4")
		(26 "In12.Cu" signal "GND5")
		(28 "In13.Cu" signal "IN5")
		(30 "In14.Cu" signal "GND6")
		(32 "In15.Cu" signal "IN6")
		(34 "In16.Cu" signal "GND7")
		(2 "B.Cu" signal "BOTTOM")
		(9 "F.Adhes" user "F.Adhesive")
		(11 "B.Adhes" user "B.Adhesive")
		(13 "F.Paste" user "Package Geometry/Pastemask Top")
		(15 "B.Paste" user "Package Geometry/Pastemask Bottom")
		(5 "F.SilkS" user "Ref Des/Silkscreen Top")
		(7 "B.SilkS" user "Ref Des/Silkscreen Bottom")
		(1 "F.Mask" user "Board Geometry/Soldermask Top")
		(3 "B.Mask" user "Board Geometry/Soldermask Bottom")
		(17 "Dwgs.User" user "User.Drawings")
		(19 "Cmts.User" user "User.Comments")
		(21 "Eco1.User" user "User.Eco1")
		(23 "Eco2.User" user "User.Eco2")
		(25 "Edge.Cuts" user "Board Geometry/Outline")
		(27 "Margin" user)
		(31 "F.CrtYd" user "Package Geometry/Place Bound Top")
		(29 "B.CrtYd" user "Package Geometry/Place Bound Bottom")
		(35 "F.Fab" user "Ref Des/Assembly Top")
		(33 "B.Fab" user "Ref Des/Assembly Bottom")
	)
	(footprint ""
		(layer "F.Cu")
		(at 454.210674 -397.245332)
		(property "Reference" "PU6504"
			(at -2.411984 -7.177024 0)
			(unlocked yes)
			(layer "F.SilkS")
			(effects
				(font
					(size 0.7874 0.5842)
					(thickness 0.1524)
				)
				(justify left)
			)
		)
		(property "Value" ""
			(at 0 0 0)
			(layer "F.Fab")
			(effects
				(font
					(size 1.27 1.27)
				)
			)
		)
		(duplicate_pad_numbers_are_jumpers no)
		(pad "1" smd rect
			(at -2.400046 -2.275078 90)
			(size 0.2286 0.6096)
			(layers "F.Cu" "F.Mask" "F.Paste")
			(net "P0V9_RETIMER_CPU0_VOS2")
		)
		(pad "2" smd rect
			(at -2.400046 -1.82499 90)
			(size 0.2286 0.6096)
			(layers "F.Cu" "F.Mask" "F.Paste")
			(net "GND")
		)
		(pad "3" smd rect
			(at -2.400046 -1.374902 90)
			(size 0.2286 0.6096)
			(layers "F.Cu" "F.Mask" "F.Paste")
			(net "P0V9_RETIMER_CPU0_VCC2")
		)
		(pad "4" smd rect
			(at -2.400046 -0.925068 90)
			(size 0.2286 0.6096)
			(layers "F.Cu" "F.Mask" "F.Paste")
			(net "P0V9_RETIMER_CPU0_PVCC")
		)
		(pad "5" smd rect
			(at -2.400046 -0.47498 90)
			(size 0.2286 0.6096)
			(layers "F.Cu" "F.Mask" "F.Paste")
			(net "GND")
		)
		(pad "6" smd rect
			(at -2.400046 -0.024892 90)
			(size 0.2286 0.6096)
			(layers "F.Cu" "F.Mask" "F.Paste")
			(net "NC_PV09_RETIMER_CPU0_GL1_2")
		)
		(pad "7_9-20_24" smd circle
			(at 0 1.150112 90)
			(size 0 0)
			(layers "F.Cu" "F.Mask" "F.Paste")
			(net "GND")
		)
		(pad "10_19" smd rect
			(at 0 2.899918 90)
			(size 0.6096 4.318)
			(layers "F.Cu" "F.Mask" "F.Paste")
			(net "SW_P0V9_RETIMER_CPU0_SW2")
		)
		(pad "25_29" smd rect
			(at 1.549908 -1.279906 270)
			(size 2.0574 2.3114)
			(layers "F.Cu" "F.Mask" "F.Paste")
			(net "SW_P12V_AUX_P0V9_RETIMER_CPU0_FLT")
		)
		(pad "30" smd rect
			(at 2.05994 -2.899918)
			(size 0.2286 0.6096)
			(layers "F.Cu" "F.Mask" "F.Paste")
			(net "SW_P12V_AUX_P0V9_RETIMER_CPU0_FLT")
		)
		(pad "31" smd rect
			(at 1.610106 -2.899918)
			(size 0.2286 0.6096)
			(layers "F.Cu" "F.Mask" "F.Paste")
			(net "NC_PV09_RETIMER_CPU0_DNC2")
		)
		(pad "32" smd rect
			(at 1.160018 -2.899918)
			(size 0.2286 0.6096)
			(layers "F.Cu" "F.Mask" "F.Paste")
			(net "SW_P0V9_RETIMER_CPU0_PH2")
		)
		(pad "33" smd rect
			(at 0.70993 -2.899918)
			(size 0.2286 0.6096)
			(layers "F.Cu" "F.Mask" "F.Paste")
			(net "SW_P0V9_RETIMER_CPU0_BOOT2")
		)
		(pad "34" smd rect
			(at 0.260096 -2.899918)
			(size 0.2286 0.6096)
			(layers "F.Cu" "F.Mask" "F.Paste")
			(net "P0V9_RETIMER_CPU0_PWM2")
		)
		(pad "35" smd rect
			(at -0.189992 -2.899918)
			(size 0.2286 0.6096)
			(layers "F.Cu" "F.Mask" "F.Paste")
			(net "P0V9_RETIMER_CPU0_VCC2")
		)
		(pad "36" smd rect
			(at -0.64008 -2.899918)
			(size 0.2286 0.6096)
			(layers "F.Cu" "F.Mask" "F.Paste")
			(net "P0V9_RETIMER_CPU0_TEMP0")
		)
		(pad "37" smd rect
			(at -1.089914 -2.899918)
			(size 0.2286 0.6096)
			(layers "F.Cu" "F.Mask" "F.Paste")
			(net "P0V9_RETIMER_CPU0_LSET2")
		)
		(pad "38" smd rect
			(at -1.540002 -2.899918)
			(size 0.2286 0.6096)
			(layers "F.Cu" "F.Mask" "F.Paste")
			(net "P0V9_RETIMER_CPU0_IMON2")
		)
		(pad "39" smd rect
			(at -1.99009 -2.899918)
			(size 0.2286 0.6096)
			(layers "F.Cu" "F.Mask" "F.Paste")
			(net "PV09_RETIMER_CPU0_VCCS")
		)
		(pad "40" smd rect
			(at -0.87503 -1.27508)
			(size 1.7526 1.9558)
			(layers "F.Cu" "F.Mask" "F.Paste")
			(net "GND")
		)
		(pad "41" smd rect
			(at -1.525016 0.249936 270)
			(size 0.3048 0.4572)
			(layers "F.Cu" "F.Mask" "F.Paste")
			(net "NC_PV09_RETIMER_CPU0_GL2_2")
		)
	)
)
